Testpoint Report Status for Project:16315-1

Total # of Nets  : 1685

Number of nets with "No_Test" property      :   436
Number of nets with testpoints assigned >1  :   5
Number of nets with testpoints assigned =1  :   1199
Number of nets with testpoints assigned =0  :   45

Percent (All nets)                              :  71.45%
Percent (All nets Excluded "No_Test" property)  :  96.40%

GND                                        4
MB3_P12V_IN_R                              2
P12V_A                                     5
P12V_IN                                    2
P5V_A_4                                    2

12V_PRE_0                                  1
12V_PRE_1                                  1
12V_PRE_10                                 1
12V_PRE_12                                 1
12V_PRE_13                                 1
12V_PRE_14                                 1
12V_PRE_15                                 1
12V_PRE_16                                 1
12V_PRE_17                                 1
12V_PRE_18                                 1
12V_PRE_19                                 1
12V_PRE_2                                  1
12V_PRE_20                                 1
12V_PRE_21                                 1
12V_PRE_22                                 1
12V_PRE_23                                 1
12V_PRE_24                                 1
12V_PRE_25                                 1
12V_PRE_26                                 1
12V_PRE_27                                 1
12V_PRE_28                                 1
12V_PRE_29                                 1
12V_PRE_30                                 1
12V_PRE_31                                 1
12V_PRE_32                                 1
12V_PRE_33                                 1
12V_PRE_34                                 1
12V_PRE_35                                 1
12V_PRE_4                                  1
12V_PRE_5                                  1
12V_PRE_6                                  1
12V_PRE_7                                  1
12V_PRE_8                                  1
12V_PRE_9                                  1
5V_PRE_3                                   1
ACT_HDD_0                                  1
ACT_HDD_1                                  1
ACT_HDD_10                                 1
ACT_HDD_12                                 1
ACT_HDD_13                                 1
ACT_HDD_14                                 1
ACT_HDD_15                                 1
ACT_HDD_16                                 1
ACT_HDD_18                                 1
ACT_HDD_19                                 1
ACT_HDD_2                                  1
ACT_HDD_20                                 1
ACT_HDD_21                                 1
ACT_HDD_22                                 1
ACT_HDD_23                                 1
ACT_HDD_24                                 1
ACT_HDD_25                                 1
ACT_HDD_26                                 1
ACT_HDD_27                                 1
ACT_HDD_28                                 1
ACT_HDD_29                                 1
ACT_HDD_3                                  1
ACT_HDD_30                                 1
ACT_HDD_31                                 1
ACT_HDD_32                                 1
ACT_HDD_33                                 1
ACT_HDD_34                                 1
ACT_HDD_35                                 1
ACT_HDD_4                                  1
ACT_HDD_5                                  1
ACT_HDD_6                                  1
ACT_HDD_7                                  1
ACT_HDD_8                                  1
ACT_HDD_9                                  1
AGND_CURRENT_DPB                           1
AGND_CURRENT_MONOA                         1
AGND_CURRENT_MONOB                         1
AGND_P3V3_STBY                             1
AGND_P5V_A                                 1
AGND_P5V_B                                 1
AGND_P5V_C                                 1
AGND_P5V_D                                 1
BMC_A_EXP_A_SPARE_0                        1
BMC_A_EXP_A_SPARE_1                        1
BMC_A_HEARTBEAT                            1
BMC_A_MISC_ALERT_N                         1
BMC_A_TO_EXP_A_RESET_N                     1
BMC_B_EXP_B_SPARE_0                        1
BMC_B_EXP_B_SPARE_1                        1
BMC_B_HEARTBEAT                            1
BMC_B_MISC_ALERT_N                         1
BMC_B_TO_EXP_B_RESET_N                     1
COMP_A_BMC_A_ALERT_N                       1
COMP_A_BMC_A_SPARE_0                       1
COMP_A_BMC_A_SPARE_1                       1
COMP_A_EXP_A_SPARE_0                       1
COMP_A_FAST_THROTTLE_N                     1
COMP_A_INS_N                               1
COMP_A_PGOOD                               1
COMP_A_POWER_FAIL_N                        1
COMP_A_PRI_INS_N                           1
COMP_A_PWR_BTN_N                           1
COMP_A_PWR_EN                              1
COMP_A_SEC_INS_N                           1
COMP_A_TO_BMC_A_RESET_N                    1
COMP_B_BMC_B_ALERT_N                       1
COMP_B_BMC_B_SPARE_0                       1
COMP_B_BMC_B_SPARE_1                       1
COMP_B_EXP_B_SPARE_0                       1
COMP_B_FAST_THROTTLE_N                     1
COMP_B_INS_N                               1
COMP_B_PGOOD                               1
COMP_B_POWER_FAIL_N                        1
COMP_B_PRI_INS_N                           1
COMP_B_PWR_BTN_N                           1
COMP_B_PWR_EN                              1
COMP_B_SEC_INS_N                           1
COMP_B_TO_BMC_B_RESET_N                    1
DPB_PWR_BTN_A                              1
DPB_PWR_BTN_B                              1
DPB_PWR_BTN_BUF_A                          1
DPB_PWR_BTN_BUF_B                          1
DRAWER_CLOSED_N                            1
DRIVE_A_0_ACT                              1
DRIVE_A_0_FLT_LED                          1
DRIVE_A_0_INS                              1
DRIVE_A_0_PWR                              1
DRIVE_A_10_ACT                             1
DRIVE_A_10_FLT_LED                         1
DRIVE_A_10_INS                             1
DRIVE_A_10_PWR                             1
DRIVE_A_11_ACT                             1
DRIVE_A_11_FLT_LED                         1
DRIVE_A_11_INS                             1
DRIVE_A_11_PWR                             1
DRIVE_A_12_ACT                             1
DRIVE_A_12_FLT_LED                         1
DRIVE_A_12_INS                             1
DRIVE_A_12_PWR                             1
DRIVE_A_13_ACT                             1
DRIVE_A_13_FLT_LED                         1
DRIVE_A_13_INS                             1
DRIVE_A_13_PWR                             1
DRIVE_A_14_ACT                             1
DRIVE_A_14_FLT_LED                         1
DRIVE_A_14_INS                             1
DRIVE_A_14_PWR                             1
DRIVE_A_15_ACT                             1
DRIVE_A_15_FLT_LED                         1
DRIVE_A_15_INS                             1
DRIVE_A_15_PWR                             1
DRIVE_A_16_ACT                             1
DRIVE_A_16_FLT_LED                         1
DRIVE_A_16_INS                             1
DRIVE_A_16_PWR                             1
DRIVE_A_17_ACT                             1
DRIVE_A_17_FLT_LED                         1
DRIVE_A_17_INS                             1
DRIVE_A_17_PWR                             1
DRIVE_A_18_ACT                             1
DRIVE_A_18_FLT_LED                         1
DRIVE_A_18_INS                             1
DRIVE_A_18_PWR                             1
DRIVE_A_19_ACT                             1
DRIVE_A_19_FLT_LED                         1
DRIVE_A_19_INS                             1
DRIVE_A_19_PWR                             1
DRIVE_A_1_ACT                              1
DRIVE_A_1_FLT_LED                          1
DRIVE_A_1_INS                              1
DRIVE_A_1_PWR                              1
DRIVE_A_20_ACT                             1
DRIVE_A_20_FLT_LED                         1
DRIVE_A_20_INS                             1
DRIVE_A_20_PWR                             1
DRIVE_A_21_ACT                             1
DRIVE_A_21_FLT_LED                         1
DRIVE_A_21_INS                             1
DRIVE_A_21_PWR                             1
DRIVE_A_22_ACT                             1
DRIVE_A_22_FLT_LED                         1
DRIVE_A_22_INS                             1
DRIVE_A_22_PWR                             1
DRIVE_A_23_ACT                             1
DRIVE_A_23_FLT_LED                         1
DRIVE_A_23_INS                             1
DRIVE_A_23_PWR                             1
DRIVE_A_24_ACT                             1
DRIVE_A_24_FLT_LED                         1
DRIVE_A_24_INS                             1
DRIVE_A_24_PWR                             1
DRIVE_A_25_ACT                             1
DRIVE_A_25_FLT_LED                         1
DRIVE_A_25_INS                             1
DRIVE_A_25_PWR                             1
DRIVE_A_26_ACT                             1
DRIVE_A_26_FLT_LED                         1
DRIVE_A_26_INS                             1
DRIVE_A_26_PWR                             1
DRIVE_A_27_ACT                             1
DRIVE_A_27_FLT_LED                         1
DRIVE_A_27_INS                             1
DRIVE_A_27_PWR                             1
DRIVE_A_28_ACT                             1
DRIVE_A_28_FLT_LED                         1
DRIVE_A_28_INS                             1
DRIVE_A_28_PWR                             1
DRIVE_A_29_ACT                             1
DRIVE_A_29_FLT_LED                         1
DRIVE_A_29_INS                             1
DRIVE_A_29_PWR                             1
DRIVE_A_2_ACT                              1
DRIVE_A_2_FLT_LED                          1
DRIVE_A_2_INS                              1
DRIVE_A_2_PWR                              1
DRIVE_A_30_ACT                             1
DRIVE_A_30_FLT_LED                         1
DRIVE_A_30_INS                             1
DRIVE_A_30_PWR                             1
DRIVE_A_31_ACT                             1
DRIVE_A_31_FLT_LED                         1
DRIVE_A_31_INS                             1
DRIVE_A_31_PWR                             1
DRIVE_A_32_ACT                             1
DRIVE_A_32_FLT_LED                         1
DRIVE_A_32_INS                             1
DRIVE_A_32_PWR                             1
DRIVE_A_33_ACT                             1
DRIVE_A_33_FLT_LED                         1
DRIVE_A_33_INS                             1
DRIVE_A_33_PWR                             1
DRIVE_A_34_ACT                             1
DRIVE_A_34_FLT_LED                         1
DRIVE_A_34_INS                             1
DRIVE_A_34_PWR                             1
DRIVE_A_35_ACT                             1
DRIVE_A_35_FLT_LED                         1
DRIVE_A_35_INS                             1
DRIVE_A_35_PWR                             1
DRIVE_A_3_ACT                              1
DRIVE_A_3_FLT_LED                          1
DRIVE_A_3_INS                              1
DRIVE_A_3_PWR                              1
DRIVE_A_4_ACT                              1
DRIVE_A_4_FLT_LED                          1
DRIVE_A_4_INS                              1
DRIVE_A_4_PWR                              1
DRIVE_A_5_ACT                              1
DRIVE_A_5_FLT_LED                          1
DRIVE_A_5_INS                              1
DRIVE_A_5_PWR                              1
DRIVE_A_6_ACT                              1
DRIVE_A_6_FLT_LED                          1
DRIVE_A_6_INS                              1
DRIVE_A_6_PWR                              1
DRIVE_A_7_ACT                              1
DRIVE_A_7_FLT_LED                          1
DRIVE_A_7_INS                              1
DRIVE_A_7_PWR                              1
DRIVE_A_8_ACT                              1
DRIVE_A_8_FLT_LED                          1
DRIVE_A_8_INS                              1
DRIVE_A_8_PWR                              1
DRIVE_A_9_ACT                              1
DRIVE_A_9_FLT_LED                          1
DRIVE_A_9_INS                              1
DRIVE_A_9_PWR                              1
DRIVE_B_24_ACT                             1
DRIVE_B_24_FLT_LED                         1
DRIVE_B_25_ACT                             1
DRIVE_B_25_FLT_LED                         1
DRIVE_B_26_ACT                             1
DRIVE_B_26_FLT_LED                         1
DRIVE_B_27_ACT                             1
DRIVE_B_27_FLT_LED                         1
DRIVE_B_28_ACT                             1
DRIVE_B_28_FLT_LED                         1
DRIVE_B_29_ACT                             1
DRIVE_B_29_FLT_LED                         1
DRIVE_B_30_ACT                             1
DRIVE_B_30_FLT_LED                         1
DRIVE_B_31_ACT                             1
DRIVE_B_31_FLT_LED                         1
DRIVE_B_32_ACT                             1
DRIVE_B_32_FLT_LED                         1
DRIVE_B_33_ACT                             1
DRIVE_B_33_FLT_LED                         1
DRIVE_B_34_ACT                             1
DRIVE_B_34_FLT_LED                         1
DRIVE_B_35_ACT                             1
DRIVE_B_35_FLT_LED                         1
DRIVE_INSERT_ALERT_A_N                     1
DRV_ACT_0                                  1
DRV_ACT_0_N                                1
DRV_ACT_1                                  1
DRV_ACT_10                                 1
DRV_ACT_10_N                               1
DRV_ACT_11                                 1
DRV_ACT_11_N                               1
DRV_ACT_12                                 1
DRV_ACT_12_N                               1
DRV_ACT_13                                 1
DRV_ACT_13_N                               1
DRV_ACT_14                                 1
DRV_ACT_14_N                               1
DRV_ACT_15                                 1
DRV_ACT_15_N                               1
DRV_ACT_16                                 1
DRV_ACT_16_N                               1
DRV_ACT_17                                 1
DRV_ACT_17_N                               1
DRV_ACT_18                                 1
DRV_ACT_18_N                               1
DRV_ACT_19                                 1
DRV_ACT_19_N                               1
DRV_ACT_1_N                                1
DRV_ACT_2                                  1
DRV_ACT_20                                 1
DRV_ACT_20_N                               1
DRV_ACT_21                                 1
DRV_ACT_21_N                               1
DRV_ACT_22                                 1
DRV_ACT_22_N                               1
DRV_ACT_23                                 1
DRV_ACT_23_N                               1
DRV_ACT_24                                 1
DRV_ACT_24_N                               1
DRV_ACT_25                                 1
DRV_ACT_25_N                               1
DRV_ACT_26                                 1
DRV_ACT_26_N                               1
DRV_ACT_27                                 1
DRV_ACT_27_N                               1
DRV_ACT_28                                 1
DRV_ACT_28_N                               1
DRV_ACT_29                                 1
DRV_ACT_29_N                               1
DRV_ACT_2_N                                1
DRV_ACT_3                                  1
DRV_ACT_30                                 1
DRV_ACT_30_N                               1
DRV_ACT_31                                 1
DRV_ACT_31_N                               1
DRV_ACT_32                                 1
DRV_ACT_32_N                               1
DRV_ACT_33                                 1
DRV_ACT_33_N                               1
DRV_ACT_34                                 1
DRV_ACT_34_N                               1
DRV_ACT_35                                 1
DRV_ACT_35_N                               1
DRV_ACT_3_N                                1
DRV_ACT_4                                  1
DRV_ACT_4_N                                1
DRV_ACT_5                                  1
DRV_ACT_5_N                                1
DRV_ACT_6                                  1
DRV_ACT_6_N                                1
DRV_ACT_7                                  1
DRV_ACT_7_N                                1
DRV_ACT_8                                  1
DRV_ACT_8_N                                1
DRV_ACT_9                                  1
DRV_ACT_9_N                                1
EEPROM_A0                                  1
EEPROM_A1                                  1
EEPROM_A2                                  1
EEPROM_SCL                                 1
EEPROM_SDA                                 1
EEPROM_WP                                  1
ENCL_FAULT_LED_A                           1
ENCL_FAULT_LED_B                           1
FAN_0_INS_N                                1
FAN_1_INS_N                                1
FAN_2_INS_N                                1
FAN_3_INS_N                                1
FLT_HDD0                                   1
FLT_HDD018_N                               1
FLT_HDD0_N                                 1
FLT_HDD1                                   1
FLT_HDD10                                  1
FLT_HDD10_N                                1
FLT_HDD11                                  1
FLT_HDD11_N                                1
FLT_HDD12                                  1
FLT_HDD12_N                                1
FLT_HDD13                                  1
FLT_HDD13_N                                1
FLT_HDD14                                  1
FLT_HDD14_N                                1
FLT_HDD15                                  1
FLT_HDD15_N                                1
FLT_HDD16                                  1
FLT_HDD16_N                                1
FLT_HDD17                                  1
FLT_HDD17_N                                1
FLT_HDD18                                  1
FLT_HDD19                                  1
FLT_HDD19_N                                1
FLT_HDD1_N                                 1
FLT_HDD2                                   1
FLT_HDD20                                  1
FLT_HDD20_N                                1
FLT_HDD21                                  1
FLT_HDD21_N                                1
FLT_HDD22                                  1
FLT_HDD22_N                                1
FLT_HDD23                                  1
FLT_HDD23_N                                1
FLT_HDD24                                  1
FLT_HDD24_N                                1
FLT_HDD25                                  1
FLT_HDD25_N                                1
FLT_HDD26                                  1
FLT_HDD26_N                                1
FLT_HDD27                                  1
FLT_HDD27_N                                1
FLT_HDD28                                  1
FLT_HDD28_N                                1
FLT_HDD29                                  1
FLT_HDD29_N                                1
FLT_HDD2_N                                 1
FLT_HDD3                                   1
FLT_HDD30                                  1
FLT_HDD30_N                                1
FLT_HDD31                                  1
FLT_HDD31_N                                1
FLT_HDD32                                  1
FLT_HDD32_N                                1
FLT_HDD33                                  1
FLT_HDD33_N                                1
FLT_HDD34                                  1
FLT_HDD34_N                                1
FLT_HDD35                                  1
FLT_HDD35_N                                1
FLT_HDD3_N                                 1
FLT_HDD4                                   1
FLT_HDD4_N                                 1
FLT_HDD5                                   1
FLT_HDD5_N                                 1
FLT_HDD6                                   1
FLT_HDD6_N                                 1
FLT_HDD7                                   1
FLT_HDD7_N                                 1
FLT_HDD8                                   1
FLT_HDD8_N                                 1
FLT_HDD9                                   1
FLT_HDD9_N                                 1
FRONT_FAN_LED0                             1
FRONT_FAN_LED1                             1
FRONT_FAN_LED2                             1
FRONT_FAN_LED3                             1
GPIO_VCC_U7                                1
GPIO_VCC_U8                                1
GPIO_VCC_U9                                1
HDD_PRSNT_0                                1
HDD_PRSNT_1                                1
HDD_PRSNT_10                               1
HDD_PRSNT_11                               1
HDD_PRSNT_12                               1
HDD_PRSNT_13                               1
HDD_PRSNT_14                               1
HDD_PRSNT_15                               1
HDD_PRSNT_16                               1
HDD_PRSNT_18                               1
HDD_PRSNT_19                               1
HDD_PRSNT_2                                1
HDD_PRSNT_20                               1
HDD_PRSNT_21                               1
HDD_PRSNT_22                               1
HDD_PRSNT_23                               1
HDD_PRSNT_24                               1
HDD_PRSNT_25                               1
HDD_PRSNT_26                               1
HDD_PRSNT_27                               1
HDD_PRSNT_28                               1
HDD_PRSNT_29                               1
HDD_PRSNT_30                               1
HDD_PRSNT_31                               1
HDD_PRSNT_32                               1
HDD_PRSNT_33                               1
HDD_PRSNT_34                               1
HDD_PRSNT_35                               1
HDD_PRSNT_4                                1
HDD_PRSNT_5                                1
HDD_PRSNT_6                                1
HDD_PRSNT_7                                1
HDD_PRSNT_8                                1
I2C_BMC_A_COMP_A_SCL                       1
I2C_BMC_A_COMP_A_SCL_BUF                   1
I2C_BMC_A_COMP_A_SCL_R                     1
I2C_BMC_A_COMP_A_SDA                       1
I2C_BMC_A_COMP_A_SDA_BUF                   1
I2C_BMC_A_COMP_A_SDA_R                     1
I2C_BMC_A_EXP_A_SCL                        1
I2C_BMC_A_EXP_A_SDA                        1
I2C_BMC_A_EXP_B_SCL                        1
I2C_BMC_A_EXP_B_SDA                        1
I2C_BMC_A_MISC_SCL                         1
I2C_BMC_A_MISC_SDA                         1
I2C_BMC_B_COMP_B_SCL                       1
I2C_BMC_B_COMP_B_SCL_BUF                   1
I2C_BMC_B_COMP_B_SCL_R                     1
I2C_BMC_B_COMP_B_SDA                       1
I2C_BMC_B_COMP_B_SDA_BUF                   1
I2C_BMC_B_COMP_B_SDA_R                     1
I2C_BMC_B_EXP_A_SCL                        1
I2C_BMC_B_EXP_A_SDA                        1
I2C_BMC_B_EXP_B_SCL                        1
I2C_BMC_B_EXP_B_SDA                        1
I2C_BMC_B_MISC_SCL                         1
I2C_BMC_B_MISC_SDA                         1
I2C_CLIP_A_SCL                             1
I2C_CLIP_A_SDA                             1
I2C_DPB_A_SCL                              1
I2C_DPB_A_SCL_BUF                          1
I2C_DPB_A_SDA                              1
I2C_DPB_A_SDA_BUF                          1
I2C_DPB_BUFF_EN                            1
I2C_DPB_BUFF_READY                         1
I2C_DPB_B_SCL                              1
I2C_DPB_B_SDA                              1
I2C_DRIVE_A_FLT_LED_SCL                    1
I2C_DRIVE_A_FLT_LED_SDA                    1
I2C_DRIVE_A_INS_SCL                        1
I2C_DRIVE_A_INS_SDA                        1
I2C_DRIVE_A_PWR_SCL                        1
I2C_DRIVE_A_PWR_SDA                        1
I2C_DRIVE_B_FLT_LED_SCL                    1
I2C_DRIVE_B_FLT_LED_SDA                    1
I2C_SCC_A_SCL                              1
I2C_SCC_A_SCL_BUF                          1
I2C_SCC_A_SDA                              1
I2C_SCC_A_SDA_BUF                          1
I2C_SCC_BUFF_EN                            1
I2C_SCC_BUFF_READY                         1
I2C_SCC_B_SCL                              1
I2C_SCC_B_SDA                              1
IOM_A_FAULT_LED                            1
IOM_A_INS_N                                1
IOM_A_MATED_N                              1
IOM_A_PWR_LED                              1
IOM_A_SLOT_ID_0                            1
IOM_A_SLOT_ID_1                            1
IOM_B_FAULT_LED                            1
IOM_B_INS_N                                1
IOM_B_MATED_N                              1
IOM_B_PWR_LED                              1
IOM_B_SLOT_ID_0                            1
IOM_B_SLOT_ID_1                            1
IO_EXP0_HDD_FAULT_A0                       1
IO_EXP0_HDD_FAULT_A1                       1
IO_EXP0_HDD_FAULT_A2                       1
IO_EXP0_INT_N                              1
IO_EXP0_LED_SCL                            1
IO_EXP0_LED_SDA                            1
IO_EXP10_A0                                1
IO_EXP10_A1                                1
IO_EXP10_A2                                1
IO_EXP10_SCL                               1
IO_EXP10_SDA                               1
IO_EXP11_A0                                1
IO_EXP11_A1                                1
IO_EXP11_A2                                1
IO_EXP11_SCL                               1
IO_EXP11_SDA                               1
IO_EXP1_A0                                 1
IO_EXP1_A1                                 1
IO_EXP1_A2                                 1
IO_EXP1_HDD_FAULT_A0                       1
IO_EXP1_HDD_FAULT_A1                       1
IO_EXP1_HDD_FAULT_A2                       1
IO_EXP1_HDD_FAULT_INT_N                    1
IO_EXP1_INT_N                              1
IO_EXP1_LED_SCL                            1
IO_EXP1_LED_SDA                            1
IO_EXP1_SCL                                1
IO_EXP1_SDA                                1
IO_EXP2_A0                                 1
IO_EXP2_A1                                 1
IO_EXP2_A2                                 1
IO_EXP2_HDD_FAULT_A0                       1
IO_EXP2_HDD_FAULT_A1                       1
IO_EXP2_HDD_FAULT_A2                       1
IO_EXP2_HDD_FAULT_INT_N                    1
IO_EXP2_INT_N                              1
IO_EXP2_LED_SCL                            1
IO_EXP2_LED_SDA                            1
IO_EXP2_SCL                                1
IO_EXP2_SDA                                1
IO_EXP3_A0                                 1
IO_EXP3_A1                                 1
IO_EXP3_A2                                 1
IO_EXP3_HDD_FAULT_A0                       1
IO_EXP3_HDD_FAULT_A1                       1
IO_EXP3_HDD_FAULT_A2                       1
IO_EXP3_HDD_FAULT_INT_N                    1
IO_EXP3_INT_N                              1
IO_EXP3_LED_SCL                            1
IO_EXP3_LED_SDA                            1
IO_EXP3_SCL                                1
IO_EXP3_SDA                                1
IO_EXP4_A0                                 1
IO_EXP4_A1                                 1
IO_EXP4_A2                                 1
IO_EXP4_INT_N                              1
IO_EXP4_SCL                                1
IO_EXP4_SDA                                1
IO_EXP5_A0                                 1
IO_EXP5_A1                                 1
IO_EXP5_A2                                 1
IO_EXP5_INT_N                              1
IO_EXP5_SCL                                1
IO_EXP5_SDA                                1
IO_EXP6_A0                                 1
IO_EXP6_A1                                 1
IO_EXP6_A2                                 1
IO_EXP6_INT_N                              1
IO_EXP6_SCL                                1
IO_EXP6_SDA                                1
MB0_12V_CTRL_GATE1                         1
MB0_CM_ADR1_R                              1
MB0_CM_ADR2_R                              1
MB0_CM_GATE                                1
MB0_CM_GATE_C                              1
MB0_CM_GATE_R                              1
MB0_CM_OV_R                                1
MB0_CM_SENSE_N                             1
MB0_CM_SENSE_P                             1
MB0_CM_SENSE_R1_N                          1
MB0_CM_SENSE_R1_P                          1
MB0_CM_UV_R                                1
MB0_CM_VOUT_R                              1
MB0_HS_ENABLE                              1
MB0_HS_SENSE_N                             1
MB0_HS_SENSE_P                             1
MB0_ISET_R                                 1
MB0_ISTART_R                               1
MB0_P12V_HS                                1
MB0_P12V_PWGIN_R                           1
MB0_P12V_R                                 1
MB0_PSET_R                                 1
MB0_RETRY_R                                1
MB0_SCL_R                                  1
MB0_SDA_R                                  1
MB0_SPISS_PD                               1
MB0_TEMP                                   1
MB0_TEMP_B                                 1
MB0_TEMP_E                                 1
MB0_TIME_R                                 1
MB0_VCAP_R                                 1
MB1_12V_CTRL_GATE1                         1
MB1_CM_ADR1_R                              1
MB1_CM_ADR2_R                              1
MB1_CM_GATE                                1
MB1_CM_GATE_C                              1
MB1_CM_GATE_R                              1
MB1_CM_OV_R                                1
MB1_CM_SENSE_N                             1
MB1_CM_SENSE_P                             1
MB1_CM_SENSE_R1_N                          1
MB1_CM_SENSE_R1_P                          1
MB1_CM_UV_R                                1
MB1_CM_VOUT_R                              1
MB1_HS_ENABLE                              1
MB1_HS_SENSE_N                             1
MB1_HS_SENSE_P                             1
MB1_ISET_R                                 1
MB1_ISTART_R                               1
MB1_P12V_B_R                               1
MB1_P12V_HS                                1
MB1_P12V_PWGIN_R                           1
MB1_PSET_R                                 1
MB1_RETRY_R                                1
MB1_SCL_R                                  1
MB1_SDA_R                                  1
MB1_SPISS_PD                               1
MB1_TEMP                                   1
MB1_TEMP_B                                 1
MB1_TEMP_E                                 1
MB1_TIME_R                                 1
MB1_VCAP_R                                 1
MB3_12V_CTRL_GATE1                         1
MB3_12V_CTRL_GATE2                         1
MB3_12V_CTRL_GATE3                         1
MB3_CM_ADR1_R                              1
MB3_CM_ADR2_R                              1
MB3_CM_GATE                                1
MB3_CM_GATE_C                              1
MB3_CM_GATE_R                              1
MB3_CM_OV_R                                1
MB3_CM_SENSE_N                             1
MB3_CM_SENSE_P                             1
MB3_CM_SENSE_R1_N                          1
MB3_CM_SENSE_R1_P                          1
MB3_CM_UV_R                                1
MB3_CM_VOUT_R                              1
MB3_HS_ENABLE                              1
MB3_ISET_R                                 1
MB3_ISTART_R                               1
MB3_P12V_HS                                1
MB3_P12V_PWGIN_R                           1
MB3_PSET_R                                 1
MB3_RETRY_R                                1
MB3_SCL_R                                  1
MB3_SDA_R                                  1
MB3_SPISS_PD                               1
MB3_TEMP                                   1
MB3_TEMP_B                                 1
MB3_TEMP_E                                 1
MB3_TIME_R                                 1
MB3_VCAP_R                                 1
P12V_A_COMP                                1
P12V_A_PGOOD                               1
P12V_A_VDD_U20                             1
P12V_A_VDD_U21                             1
P12V_A_VDD_U22                             1
P12V_A_VDD_U27                             1
P12V_A_VIN_U20                             1
P12V_A_VIN_U21                             1
P12V_A_VIN_U22                             1
P12V_A_VIN_U27                             1
P12V_B                                     1
P12V_B_COMP                                1
P12V_B_PGOOD                               1
P12V_HDD0                                  1
P12V_HDD1                                  1
P12V_HDD10                                 1
P12V_HDD11                                 1
P12V_HDD12                                 1
P12V_HDD13                                 1
P12V_HDD14                                 1
P12V_HDD15                                 1
P12V_HDD16                                 1
P12V_HDD17                                 1
P12V_HDD18                                 1
P12V_HDD19                                 1
P12V_HDD2                                  1
P12V_HDD20                                 1
P12V_HDD21                                 1
P12V_HDD22                                 1
P12V_HDD23                                 1
P12V_HDD24                                 1
P12V_HDD25                                 1
P12V_HDD26                                 1
P12V_HDD27                                 1
P12V_HDD28                                 1
P12V_HDD29                                 1
P12V_HDD3                                  1
P12V_HDD30                                 1
P12V_HDD31                                 1
P12V_HDD32                                 1
P12V_HDD33                                 1
P12V_HDD34                                 1
P12V_HDD35                                 1
P12V_HDD4                                  1
P12V_HDD5                                  1
P12V_HDD6                                  1
P12V_HDD7                                  1
P12V_HDD8                                  1
P12V_HDD9                                  1
P12V_IN_PGOOD                              1
P3V3_A_BIAS                                1
P3V3_BIAS                                  1
P3V3_B_BIAS                                1
P3V3_IN_BIAS                               1
P3V3_SENSE                                 1
P3V3_STBY_A                                1
P3V3_STBY_B                                1
P3V3_STBY_CC                               1
P3V3_STBY_CC_R                             1
P3V3_STBY_EN_R                             1
P3V3_STBY_SNB                              1
P3V3_STBY_SS                               1
P3V3_STBY_SW                               1
P3V3_STBY_VBST                             1
P3V3_STBY_VBST_RR                          1
P3V3_STBY_VCC                              1
P3V3_STBY_VFB                              1
P3V3_STBY_VFB_R                            1
P3V3_STBY_VIN                              1
P3V3_STBY_VO                               1
P3V3_STBY_VRG5                             1
P5V_A_1                                    1
P5V_A_1_PGOOD                              1
P5V_A_1_SENSE                              1
P5V_A_2                                    1
P5V_A_2_PGOOD                              1
P5V_A_2_SENSE                              1
P5V_A_3                                    1
P5V_A_3_PGOOD                              1
P5V_A_3_SENSE                              1
P5V_A_4_PGOOD                              1
P5V_A_4_SENSE                              1
P5V_A_CC                                   1
P5V_A_EN_R                                 1
P5V_A_LL                                   1
P5V_A_LL_R                                 1
P5V_A_MODE                                 1
P5V_A_RF                                   1
P5V_A_ROVP                                 1
P5V_A_TRIP                                 1
P5V_A_VBST                                 1
P5V_A_VBST_RC                              1
P5V_A_VFB                                  1
P5V_A_VFB_R                                1
P5V_A_VREG                                 1
P5V_B                                      1
P5V_B_CC                                   1
P5V_B_EN_R                                 1
P5V_B_LL                                   1
P5V_B_LL_R                                 1
P5V_B_MODE                                 1
P5V_B_RF                                   1
P5V_B_ROVP                                 1
P5V_B_SNB                                  1
P5V_B_TRIP                                 1
P5V_B_VBST                                 1
P5V_B_VBST_RC                              1
P5V_B_VFB                                  1
P5V_B_VFB_R                                1
P5V_B_VREG                                 1
P5V_C_CC                                   1
P5V_C_EN_R                                 1
P5V_C_LL                                   1
P5V_C_LL_R                                 1
P5V_C_MODE                                 1
P5V_C_RF                                   1
P5V_C_ROVP                                 1
P5V_C_SNB                                  1
P5V_C_TRIP                                 1
P5V_C_VBST                                 1
P5V_C_VBST_RC                              1
P5V_C_VFB                                  1
P5V_C_VFB_R                                1
P5V_C_VREG                                 1
P5V_D_CC                                   1
P5V_D_EN_R                                 1
P5V_D_LL_R                                 1
P5V_D_MODE                                 1
P5V_D_RF                                   1
P5V_D_ROVP                                 1
P5V_D_SNB                                  1
P5V_D_TRIP                                 1
P5V_D_VBST                                 1
P5V_D_VBST_RC                              1
P5V_D_VFB                                  1
P5V_D_VFB_R                                1
P5V_D_VREG                                 1
P5V_HDD0                                   1
P5V_HDD1                                   1
P5V_HDD10                                  1
P5V_HDD11                                  1
P5V_HDD12                                  1
P5V_HDD13                                  1
P5V_HDD14                                  1
P5V_HDD15                                  1
P5V_HDD16                                  1
P5V_HDD17                                  1
P5V_HDD18                                  1
P5V_HDD19                                  1
P5V_HDD2                                   1
P5V_HDD20                                  1
P5V_HDD21                                  1
P5V_HDD22                                  1
P5V_HDD23                                  1
P5V_HDD24                                  1
P5V_HDD25                                  1
P5V_HDD26                                  1
P5V_HDD27                                  1
P5V_HDD28                                  1
P5V_HDD29                                  1
P5V_HDD3                                   1
P5V_HDD30                                  1
P5V_HDD31                                  1
P5V_HDD32                                  1
P5V_HDD33                                  1
P5V_HDD34                                  1
P5V_HDD35                                  1
P5V_HDD4                                   1
P5V_HDD5                                   1
P5V_HDD6                                   1
P5V_HDD7                                   1
P5V_HDD8                                   1
P5V_HDD9                                   1
P5V_SNB                                    1
P5V_USB_A                                  1
P5V_USB_B                                  1
PCIE_COMP_A_PCIE_RST_1                     1
PCIE_COMP_A_RST_5                          1
PCIE_COMP_A_TO_IOM_A_RST_2                 1
PCIE_COMP_A_TO_IOM_A_RST_3                 1
PCIE_COMP_A_TO_IOM_A_RST_4                 1
PCIE_COMP_A_TO_SCC_A_RST_0                 1
PCIE_COMP_B_PCIE_RST_1                     1
PCIE_COMP_B_RST_5                          1
PCIE_COMP_B_TO_IOM_B_RST_2                 1
PCIE_COMP_B_TO_IOM_B_RST_3                 1
PCIE_COMP_B_TO_IOM_B_RST_4                 1
PCIE_COMP_B_TO_SCC_B_RST_0                 1
PWM_BMC_A_ZONE_C                           1
PWM_BMC_A_ZONE_D                           1
PWM_BMC_B_ZONE_C                           1
PWM_BMC_B_ZONE_D                           1
PWM_SCC_A_ZONE_C                           1
PWM_SCC_A_ZONE_D                           1
PWRGD_P3V3_STBY                            1
RST_BTN_A_N                                1
RST_BTN_B_N                                1
SCC_A_FAULT_LED                            1
SCC_A_FULL_PGOOD                           1
SCC_A_FULL_PWR_EN                          1
SCC_A_FULL_PWR_EN_12V                      1
SCC_A_HEARTBEAT                            1
SCC_A_HS_EN                                1
SCC_A_INS_N                                1
SCC_A_PWR_LED                              1
SCC_A_RESET_N                              1
SCC_A_SLOT_ID_0                            1
SCC_A_SLOT_ID_1                            1
SCC_A_STBY_PGOOD                           1
SCC_A_STBY_PWR_EN                          1
SCC_A_TYPE_0                               1
SCC_A_TYPE_1                               1
SCC_A_TYPE_2                               1
SCC_A_TYPE_3                               1
SCC_B_FAULT_LED                            1
SCC_B_FULL_PGOOD                           1
SCC_B_FULL_PWR_EN                          1
SCC_B_HEARTBEAT                            1
SCC_B_INS_N                                1
SCC_B_PWR_LED                              1
SCC_B_RESET_N                              1
SCC_B_STBY_PGOOD                           1
SCC_B_STBY_PWR_EN                          1
SCC_B_TYPE_0                               1
SCC_B_TYPE_1                               1
SCC_B_TYPE_2                               1
SCC_B_TYPE_3                               1
SCC_FULL_PWR_EN_5V                         1
SCC_FULL_PWR_EN_5V_R                       1
SLOT1_SVR_ID0_GPIO0                        1
SLOT1_SVR_ID0_GPIO1                        1
SLOT1_SVR_ID0_GPIO2                        1
SLOT1_SVR_ID0_GPIO3                        1
SLOT3_SVR_ID0_GPIO0                        1
SLOT3_SVR_ID0_GPIO1                        1
SLOT3_SVR_ID0_GPIO2                        1
SLOT3_SVR_ID0_GPIO3                        1
SW_HDD_G0                                  1
SW_HDD_G1                                  1
SW_HDD_G10                                 1
SW_HDD_G11                                 1
SW_HDD_G12                                 1
SW_HDD_G13                                 1
SW_HDD_G14                                 1
SW_HDD_G15                                 1
SW_HDD_G16                                 1
SW_HDD_G17                                 1
SW_HDD_G18                                 1
SW_HDD_G19                                 1
SW_HDD_G2                                  1
SW_HDD_G20                                 1
SW_HDD_G21                                 1
SW_HDD_G22                                 1
SW_HDD_G23                                 1
SW_HDD_G24                                 1
SW_HDD_G25                                 1
SW_HDD_G26                                 1
SW_HDD_G27                                 1
SW_HDD_G28                                 1
SW_HDD_G29                                 1
SW_HDD_G3                                  1
SW_HDD_G30                                 1
SW_HDD_G31                                 1
SW_HDD_G32                                 1
SW_HDD_G33                                 1
SW_HDD_G34                                 1
SW_HDD_G35                                 1
SW_HDD_G4                                  1
SW_HDD_G5                                  1
SW_HDD_G6                                  1
SW_HDD_G7                                  1
SW_HDD_G8                                  1
SW_HDD_G9                                  1
SW_HDD_N0                                  1
SW_HDD_N1                                  1
SW_HDD_N10                                 1
SW_HDD_N11                                 1
SW_HDD_N12                                 1
SW_HDD_N13                                 1
SW_HDD_N14                                 1
SW_HDD_N15                                 1
SW_HDD_N16                                 1
SW_HDD_N17                                 1
SW_HDD_N18                                 1
SW_HDD_N19                                 1
SW_HDD_N2                                  1
SW_HDD_N20                                 1
SW_HDD_N21                                 1
SW_HDD_N22                                 1
SW_HDD_N23                                 1
SW_HDD_N24                                 1
SW_HDD_N25                                 1
SW_HDD_N26                                 1
SW_HDD_N27                                 1
SW_HDD_N28                                 1
SW_HDD_N29                                 1
SW_HDD_N3                                  1
SW_HDD_N30                                 1
SW_HDD_N31                                 1
SW_HDD_N32                                 1
SW_HDD_N33                                 1
SW_HDD_N34                                 1
SW_HDD_N35                                 1
SW_HDD_N4                                  1
SW_HDD_N5                                  1
SW_HDD_N6                                  1
SW_HDD_N7                                  1
SW_HDD_N8                                  1
SW_HDD_N9                                  1
SW_HDD_P0                                  1
SW_HDD_P1                                  1
SW_HDD_P10                                 1
SW_HDD_P11                                 1
SW_HDD_P12                                 1
SW_HDD_P13                                 1
SW_HDD_P14                                 1
SW_HDD_P15                                 1
SW_HDD_P16                                 1
SW_HDD_P17                                 1
SW_HDD_P18                                 1
SW_HDD_P19                                 1
SW_HDD_P2                                  1
SW_HDD_P20                                 1
SW_HDD_P21                                 1
SW_HDD_P22                                 1
SW_HDD_P23                                 1
SW_HDD_P24                                 1
SW_HDD_P25                                 1
SW_HDD_P26                                 1
SW_HDD_P27                                 1
SW_HDD_P28                                 1
SW_HDD_P29                                 1
SW_HDD_P3                                  1
SW_HDD_P30                                 1
SW_HDD_P31                                 1
SW_HDD_P32                                 1
SW_HDD_P33                                 1
SW_HDD_P34                                 1
SW_HDD_P35                                 1
SW_HDD_P4                                  1
SW_HDD_P5                                  1
SW_HDD_P6                                  1
SW_HDD_P7                                  1
SW_HDD_P8                                  1
SW_HDD_P9                                  1
SW_HDD_R0                                  1
SW_HDD_R1                                  1
SW_HDD_R10                                 1
SW_HDD_R11                                 1
SW_HDD_R12                                 1
SW_HDD_R13                                 1
SW_HDD_R14                                 1
SW_HDD_R15                                 1
SW_HDD_R16                                 1
SW_HDD_R17                                 1
SW_HDD_R18                                 1
SW_HDD_R19                                 1
SW_HDD_R2                                  1
SW_HDD_R20                                 1
SW_HDD_R21                                 1
SW_HDD_R22                                 1
SW_HDD_R23                                 1
SW_HDD_R24                                 1
SW_HDD_R25                                 1
SW_HDD_R26                                 1
SW_HDD_R27                                 1
SW_HDD_R28                                 1
SW_HDD_R29                                 1
SW_HDD_R3                                  1
SW_HDD_R30                                 1
SW_HDD_R31                                 1
SW_HDD_R32                                 1
SW_HDD_R33                                 1
SW_HDD_R34                                 1
SW_HDD_R35                                 1
SW_HDD_R4                                  1
SW_HDD_R5                                  1
SW_HDD_R6                                  1
SW_HDD_R7                                  1
SW_HDD_R8                                  1
SW_HDD_R9                                  1
SW_PWR_R_HDD0                              1
SW_PWR_R_HDD1                              1
SW_PWR_R_HDD10                             1
SW_PWR_R_HDD11                             1
SW_PWR_R_HDD12                             1
SW_PWR_R_HDD13                             1
SW_PWR_R_HDD14                             1
SW_PWR_R_HDD15                             1
SW_PWR_R_HDD16                             1
SW_PWR_R_HDD17                             1
SW_PWR_R_HDD18                             1
SW_PWR_R_HDD19                             1
SW_PWR_R_HDD2                              1
SW_PWR_R_HDD20                             1
SW_PWR_R_HDD21                             1
SW_PWR_R_HDD22                             1
SW_PWR_R_HDD23                             1
SW_PWR_R_HDD24                             1
SW_PWR_R_HDD25                             1
SW_PWR_R_HDD26                             1
SW_PWR_R_HDD27                             1
SW_PWR_R_HDD28                             1
SW_PWR_R_HDD29                             1
SW_PWR_R_HDD3                              1
SW_PWR_R_HDD30                             1
SW_PWR_R_HDD31                             1
SW_PWR_R_HDD32                             1
SW_PWR_R_HDD33                             1
SW_PWR_R_HDD34                             1
SW_PWR_R_HDD35                             1
SW_PWR_R_HDD4                              1
SW_PWR_R_HDD5                              1
SW_PWR_R_HDD6                              1
SW_PWR_R_HDD7                              1
SW_PWR_R_HDD8                              1
SW_PWR_R_HDD9                              1
SYS_A_RESET_BUFFER_N                       1
SYS_A_RESET_N                              1
SYS_B_RESET_BUFFER_N                       1
SYS_B_RESET_N                              1
SYS_PWR_LED_A                              1
SYS_PWR_LED_B                              1
TP_COMP_A_KR_P0_RX_DN                      1
TP_COMP_A_KR_P0_RX_DP                      1
TP_COMP_A_KR_P0_TX_DN                      1
TP_COMP_A_KR_P0_TX_DP                      1
TP_COMP_A_NCSI_CRSDV                       1
TP_COMP_A_NCSI_RCLK                        1
TP_COMP_A_NCSI_RXD0                        1
TP_COMP_A_NCSI_RXD1                        1
TP_COMP_A_NCSI_RXER                        1
TP_COMP_A_NCSI_TXD0                        1
TP_COMP_A_NCSI_TXD1                        1
TP_COMP_A_NCSI_TXEN                        1
TP_COMP_A_SATA_P0_RX_DN                    1
TP_COMP_A_SATA_P0_RX_DP                    1
TP_COMP_A_SATA_P0_TX_DN                    1
TP_COMP_A_SATA_P0_TX_DP                    1
TP_COMP_B_KR_P0_RX_DN                      1
TP_COMP_B_KR_P0_RX_DP                      1
TP_COMP_B_KR_P0_TX_DN                      1
TP_COMP_B_KR_P0_TX_DP                      1
TP_COMP_B_NCSI_CRSDV                       1
TP_COMP_B_NCSI_RCLK                        1
TP_COMP_B_NCSI_RXD0                        1
TP_COMP_B_NCSI_RXD1                        1
TP_COMP_B_NCSI_RXER                        1
TP_COMP_B_NCSI_TXD0                        1
TP_COMP_B_NCSI_TXD1                        1
TP_COMP_B_NCSI_TXEN                        1
TP_COMP_B_SATA_P0_RX_DN                    1
TP_COMP_B_SATA_P0_RX_DP                    1
TP_COMP_B_SATA_P0_TX_DN                    1
TP_COMP_B_SATA_P0_TX_DP                    1
TP_SMB_COMP_A_NIC_ALERT_N                  1
TP_SMB_COMP_A_NIC_SCL                      1
TP_SMB_COMP_A_NIC_SDA                      1
TP_SMB_COMP_B_NIC_ALERT_N                  1
TP_SMB_COMP_B_NIC_SCL                      1
TP_SMB_COMP_B_NIC_SDA                      1
TXS0102_A_OE                               1
TXS0102_B_OE                               1
UART_COMP_A_RX                             1
UART_COMP_A_TX                             1
UART_COMP_B_RX                             1
UART_COMP_B_TX                             1
UART_EXP_A_RX                              1
UART_EXP_A_TX                              1
UART_EXP_B_RX                              1
UART_EXP_B_TX                              1
UART_IOC_A_RX                              1
UART_IOC_A_TX                              1
UART_IOC_B_RX                              1
UART_IOC_B_TX                              1
UART_SDB_A_RX                              1
UART_SDB_A_TX                              1
UART_SDB_B_RX                              1
UART_SDB_B_TX                              1
USB_EN_1                                   1
USB_EN_2                                   1
USB_OCS_N1                                 1
USB_OCS_N2                                 1
VCCP                                       1
VCCP_A                                     1
VCCP_B                                     1
VCCP_IN                                    1
VOL_SEN_ADDR0                              1
VOL_SEN_ADDR1                              1
VOL_SEN_INT_N                              1
VOL_SEN_SCL                                1
VOL_SEN_SDA                                1

12V_PRE_11                                 0
12V_PRE_3                                  0
5V_PRE_0                                   0
5V_PRE_1                                   0
5V_PRE_10                                  0
5V_PRE_11                                  0
5V_PRE_12                                  0
5V_PRE_13                                  0
5V_PRE_14                                  0
5V_PRE_15                                  0
5V_PRE_16                                  0
5V_PRE_17                                  0
5V_PRE_18                                  0
5V_PRE_19                                  0
5V_PRE_2                                   0
5V_PRE_20                                  0
5V_PRE_21                                  0
5V_PRE_22                                  0
5V_PRE_23                                  0
5V_PRE_24                                  0
5V_PRE_25                                  0
5V_PRE_26                                  0
5V_PRE_27                                  0
5V_PRE_28                                  0
5V_PRE_29                                  0
5V_PRE_30                                  0
5V_PRE_31                                  0
5V_PRE_32                                  0
5V_PRE_33                                  0
5V_PRE_34                                  0
5V_PRE_35                                  0
5V_PRE_4                                   0
5V_PRE_5                                   0
5V_PRE_6                                   0
5V_PRE_7                                   0
5V_PRE_8                                   0
5V_PRE_9                                   0
ACT_HDD_11                                 0
ACT_HDD_17                                 0
HDD_PRSNT_17                               0
HDD_PRSNT_3                                0
HDD_PRSNT_9                                0
MB3_HS_SENSE_N                             0
MB3_HS_SENSE_P                             0
P5V_D_LL                                   0
